# T6G (Grand Teton) — schematic netlist excerpt (pin names and nets, part order shuffled) for the footprints in the layout excerpt that follows; sources: Cadence DE-HDL packaged netlist, KiCad conversion of 04192023_DAF0TMB3IC0_F0TG_MB_C_brd_V02_OCP.brd

PL71  Q_INDUCTOR  BLM18SN220TN1D/8000MA IND  pkg SMLF  page 192 : \1\ = P12V_AUX ; \2\ = SW_P12V_AUX_PVDD_33_S5_FLT

(kicad_pcb
	(version 20260206)
	(generator "pcbnew")
	(generator_version "10.0")
	(general
		(thickness 1.6)
		(legacy_teardrops no)
	)
	(paper "A4")
	(title_block
		(title "04192023_DAF0TMB3IC0_F0TG_MB_C_brd_V02_OCP.brd")
		(comment 1 "Grand Teton / footprints 1167-1167 of 8354")
	)
	(layers
		(0 "F.Cu" signal "TOP")
		(4 "In1.Cu" signal "GND")
		(6 "In2.Cu" signal "IN1")
		(8 "In3.Cu" signal "GND1")
		(10 "In4.Cu" signal "IN2")
		(12 "In5.Cu" signal "GND2")
		(14 "In6.Cu" signal "IN3")
		(16 "In7.Cu" signal "GND3")
		(18 "In8.Cu" signal "VCC")
		(20 "In9.Cu" signal "VCC1")
		(22 "In10.Cu" signal "GND4")
		(24 "In11.Cu" signal "IN4")
		(26 "In12.Cu" signal "GND5")
		(28 "In13.Cu" signal "IN5")
		(30 "In14.Cu" signal "GND6")
		(32 "In15.Cu" signal "IN6")
		(34 "In16.Cu" signal "GND7")
		(2 "B.Cu" signal "BOTTOM")
		(9 "F.Adhes" user "F.Adhesive")
		(11 "B.Adhes" user "B.Adhesive")
		(13 "F.Paste" user "Package Geometry/Pastemask Top")
		(15 "B.Paste" user "Package Geometry/Pastemask Bottom")
		(5 "F.SilkS" user "Ref Des/Silkscreen Top")
		(7 "B.SilkS" user "Ref Des/Silkscreen Bottom")
		(1 "F.Mask" user "Board Geometry/Soldermask Top")
		(3 "B.Mask" user "Board Geometry/Soldermask Bottom")
		(17 "Dwgs.User" user "User.Drawings")
		(19 "Cmts.User" user "User.Comments")
		(21 "Eco1.User" user "User.Eco1")
		(23 "Eco2.User" user "User.Eco2")
		(25 "Edge.Cuts" user "Board Geometry/Outline")
		(27 "Margin" user)
		(31 "F.CrtYd" user "Package Geometry/Place Bound Top")
		(29 "B.CrtYd" user "Package Geometry/Place Bound Bottom")
		(35 "F.Fab" user "Ref Des/Assembly Top")
		(33 "B.Fab" user "Ref Des/Assembly Bottom")
	)
	(footprint ""
		(layer "F.Cu")
		(at 203.310744 -346.505022 180)
		(property "Reference" "PL71"
			(at 0 0 180)
			(layer "F.SilkS")
			(hide yes)
			(effects
				(font
					(size 1.27 1.27)
				)
			)
		)
		(property "Value" ""
			(at 0 0 180)
			(layer "F.Fab")
			(effects
				(font
					(size 1.27 1.27)
				)
			)
		)
		(duplicate_pad_numbers_are_jumpers no)
		(fp_line
			(start 1.27 0.5842)
			(end 1.27 -0.5842)
			(stroke
				(width 0.1524)
				(type default)
			)
			(layer "F.SilkS")
		)
		(fp_line
			(start 1.27 0.5842)
			(end -1.27 0.5842)
			(stroke
				(width 0.1524)
				(type default)
			)
			(layer "F.SilkS")
		)
		(fp_line
			(start -1.27 0.5842)
			(end -1.27 -0.5842)
			(stroke
				(width 0.1524)
				(type default)
			)
			(layer "F.SilkS")
		)
		(fp_line
			(start -1.27 -0.5588)
			(end -1.27 -0.5842)
			(stroke
				(width 0.1524)
				(type default)
			)
			(layer "F.SilkS")
		)
		(fp_line
			(start -1.27 -0.5842)
			(end 1.27 -0.5842)
			(stroke
				(width 0.1524)
				(type default)
			)
			(layer "F.SilkS")
		)
		(fp_line
			(start 1.1938 0.4064)
			(end 0.9144 0.4064)
			(stroke
				(width 0.1)
				(type default)
			)
			(layer "F.Fab")
		)
		(fp_line
			(start 1.1938 -0.406654)
			(end 1.1938 0.4064)
			(stroke
				(width 0.1)
				(type default)
			)
			(layer "F.Fab")
		)
		(fp_line
			(start 0.9144 0.508)
			(end -0.9144 0.508)
			(stroke
				(width 0.1)
				(type default)
			)
			(layer "F.Fab")
		)
		(fp_line
			(start 0.9144 0.4064)
			(end 0.9144 0.508)
			(stroke
				(width 0.1)
				(type default)
			)
			(layer "F.Fab")
		)
		(fp_line
			(start 0.9144 -0.406654)
			(end 1.1938 -0.406654)
			(stroke
				(width 0.1)
				(type default)
			)
			(layer "F.Fab")
		)
		(fp_line
			(start 0.9144 -0.508)
			(end 0.9144 -0.406654)
			(stroke
				(width 0.1)
				(type default)
			)
			(layer "F.Fab")
		)
		(fp_line
			(start -0.9144 0.508)
			(end -0.9144 0.406654)
			(stroke
				(width 0.1)
				(type default)
			)
			(layer "F.Fab")
		)
		(fp_line
			(start -0.9144 0.406654)
			(end -1.194308 0.406654)
			(stroke
				(width 0.1)
				(type default)
			)
			(layer "F.Fab")
		)
		(fp_line
			(start -0.9144 -0.406654)
			(end -0.9144 -0.508)
			(stroke
				(width 0.1)
				(type default)
			)
			(layer "F.Fab")
		)
		(fp_line
			(start -0.9144 -0.508)
			(end 0.9144 -0.508)
			(stroke
				(width 0.1)
				(type default)
			)
			(layer "F.Fab")
		)
		(fp_line
			(start -1.194308 0.406654)
			(end -1.194308 -0.406654)
			(stroke
				(width 0.1)
				(type default)
			)
			(layer "F.Fab")
		)
		(fp_line
			(start -1.194308 -0.406654)
			(end -0.9144 -0.406654)
			(stroke
				(width 0.1)
				(type default)
			)
			(layer "F.Fab")
		)
		(pad "1" smd rect
			(at -0.7366 0 90)
			(size 0.7112 0.8128)
			(layers "F.Cu" "F.Mask" "F.Paste")
			(net "P12V_AUX")
		)
		(pad "2" smd rect
			(at 0.7366 0 90)
			(size 0.7112 0.8128)
			(layers "F.Cu" "F.Mask" "F.Paste")
			(net "SW_P12V_AUX_PVDD_33_S5_FLT")
		)
	)
)
